#ISCELL
  mstr_misc dns *
  *
#ISCELL
  mstr_symbols cad_note *
  *
#ISCELL
  mstr_symbols intel_corp_bpage *
  *
#ISCELL
  mstr_standard offpage *
  page151_i100
#CELL
  mstr_discrete res *
  page151_i101
#ISCELL
  mstr_standard offpage *
  page151_i103
#ISCELL
  mstr_standard offpage *
  page151_i104
#ISCELL
  mstr_standard offpage *
  page151_i105
#ISCELL
  mstr_standard offpage *
  page151_i106
#ISCELL
  mstr_standard offpage *
  page151_i107
#ISCELL
  mstr_standard offpage *
  page151_i108
#ISCELL
  mstr_standard offpage *
  page151_i109
#ISCELL
  mstr_standard offpage *
  page151_i110
#ISCELL
  mstr_standard offpage *
  page151_i111
#ISCELL
  mstr_symbols gnd *
  page151_i112
#ISCELL
  mstr_standard offpage *
  page151_i113
#ISCELL
  mstr_standard offpage *
  page151_i114
#ISCELL
  mstr_standard offpage *
  page151_i115
#ISCELL
  mstr_standard offpage *
  page151_i116
#ISCELL
  mstr_standard offpage *
  page151_i117
#ISCELL
  mstr_symbols gnd *
  page151_i118
#CELL
  w_hdl sc1u16v3kx-2gp *
  page151_i120
#CELL
  w_hdl sc1u16v3kx-2gp *
  page151_i121
#ISCELL
  w_power w_vcc_circle *
  page151_i122
#CELL
  mstr_discrete cap *
  page151_i123
#ISCELL
  mstr_symbols gnd *
  page151_i124
#CELL
  mstr_discrete cap *
  page151_i125
#ISCELL
  mstr_symbols p3v3_stby *
  page151_i136
#ISCELL
  mstr_symbols gnd *
  page151_i137
#CELL
  mstr_discrete res *
  page151_i138
#CELL
  mstr_discrete cap *
  page151_i139
#CELL
  mstr_discrete cap *
  page151_i140
#CELL
  mstr_discrete cap *
  page151_i141
#CELL
  mstr_discrete cap *
  page151_i142
#CELL
  mstr_discrete cap *
  page151_i143
#CELL
  mstr_discrete led *
  page151_i144
#CELL
  mstr_discrete fet_n_dual *
  page151_i145
#ISCELL
  w_power w_vcc_circle *
  page151_i146
#ISCELL
  mstr_symbols gnd *
  page151_i149
#ISCELL
  mstr_symbols gnd *
  page151_i150
#ISCELL
  mstr_symbols p3v3_stby *
  page151_i172
#CELL
  mstr_discrete res *
  page151_i173
#ISCELL
  mstr_symbols p3v3_stby *
  page151_i174
#CELL
  mstr_discrete res *
  page151_i175
#ISCELL
  mstr_symbols gnd *
  page151_i197
#CELL
  mstr_discrete fet_n_dual *
  page151_i198
#ISCELL
  mstr_symbols gnd *
  page151_i199
#ISCELL
  w_power w_vcc_circle *
  page151_i200
#CELL
  mstr_discrete res *
  page151_i201
#CELL
  mstr_discrete res *
  page151_i202
#ISCELL
  mstr_symbols gnd *
  page151_i204
#ISCELL
  mstr_standard offpage *
  page151_i207
#ISCELL
  mstr_standard offpage *
  page151_i208
#CELL
  mstr_discrete res *
  page151_i209
#CELL
  mstr_discrete res *
  page151_i210
#CELL
  mstr_discrete res *
  page151_i211
#CELL
  dev_discrete cap_a *
  page151_i212
#CELL
  dev_discrete cap_a *
  page151_i213
#CELL
  dev_discrete cap_a *
  page151_i214
#CELL
  dev_discrete cap_a *
  page151_i215
#CELL
  dev_discrete cap_a *
  page151_i216
#CELL
  dev_discrete cap_a *
  page151_i217
#CELL
  mstr_discrete cap *
  page151_i220
#ISCELL
  mstr_symbols gnd *
  page151_i221
#CELL
  mstr_discrete res *
  page151_i222
#CELL
  w_hdl 120r2f-gp *
  page151_i223
#CELL
  w_hdl 120r2f-gp *
  page151_i224
#CELL
  w_hdl 120r2f-gp *
  page151_i225
#CELL
  w_hdl 120r2f-gp *
  page151_i226
#CELL
  w_hdl 120r2f-gp *
  page151_i227
#CELL
  w_hdl 120r2f-gp *
  page151_i228
#CELL
  w_hdl 120r2f-gp *
  page151_i229
#CELL
  w_hdl 120r2f-gp *
  page151_i230
#CELL
  w_hdl 120r2f-gp *
  page151_i231
#CELL
  w_hdl 120r2f-gp *
  page151_i232
#CELL
  w_hdl 120r2f-gp *
  page151_i233
#CELL
  w_hdl 120r2f-gp *
  page151_i234
#CELL
  w_hdl 120r2f-gp *
  page151_i235
#CELL
  w_hdl 120r2f-gp *
  page151_i236
#CELL
  w_hdl 120r2f-gp *
  page151_i237
#CELL
  w_hdl 120r2f-gp *
  page151_i238
#CELL
  w_hdl 120r2f-gp *
  page151_i239
#CELL
  w_hdl 120r2f-gp *
  page151_i240
#CELL
  w_hdl 120r2f-gp *
  page151_i241
#CELL
  w_hdl 120r2f-gp *
  page151_i242
#CELL
  w_hdl 120r2f-gp *
  page151_i243
#CELL
  w_hdl 120r2f-gp *
  page151_i244
#CELL
  w_hdl 120r2f-gp *
  page151_i245
#CELL
  w_hdl 120r2f-gp *
  page151_i246
#CELL
  w_hdl 120r2f-gp *
  page151_i247
#CELL
  w_hdl 120r2f-gp *
  page151_i248
#CELL
  w_hdl 120r2f-gp *
  page151_i249
#CELL
  w_hdl 120r2f-gp *
  page151_i250
#CELL
  w_hdl 120r2f-gp *
  page151_i251
#CELL
  w_hdl 120r2f-gp *
  page151_i252
#CELL
  w_hdl 120r2f-gp *
  page151_i253
#CELL
  w_hdl 120r2f-gp *
  page151_i254
#CELL
  w_hdl 120r2f-gp *
  page151_i255
#CELL
  w_hdl 120r2f-gp *
  page151_i256
#CELL
  w_hdl 120r2f-gp *
  page151_i257
#CELL
  w_hdl 120r2f-gp *
  page151_i258
#CELL
  w_hdl 120r2f-gp *
  page151_i259
#CELL
  w_hdl 120r2f-gp *
  page151_i260
#CELL
  w_hdl 120r2f-gp *
  page151_i261
#CELL
  w_hdl 120r2f-gp *
  page151_i262
#CELL
  w_hdl 120r2f-gp *
  page151_i263
#CELL
  w_hdl 120r2f-gp *
  page151_i264
#CELL
  w_hdl 120r2f-gp *
  page151_i265
#CELL
  w_hdl 120r2f-gp *
  page151_i266
#CELL
  w_hdl 120r2f-gp *
  page151_i267
#CELL
  w_hdl 120r2f-gp *
  page151_i268
#CELL
  w_hdl 120r2f-gp *
  page151_i269
#CELL
  w_hdl 120r2f-gp *
  page151_i270
#CELL
  w_hdl 120r2f-gp *
  page151_i271
#CELL
  w_hdl 120r2f-gp *
  page151_i274
#CELL
  w_hdl 120r2f-gp *
  page151_i275
#CELL
  mstr_discrete res *
  page151_i278
#CELL
  mstr_discrete res *
  page151_i279
#CELL
  w_hdl h5an4g6nafr-tfc-gp *
  page151_i49
#ISCELL
  mstr_standard offpage *
  page151_i50
#ISCELL
  w_power w_vcc_circle *
  page151_i51
#ISCELL
  mstr_standard offpage *
  page151_i52
#ISCELL
  w_power w_vcc_circle *
  page151_i54
#CELL
  mstr_discrete res *
  page151_i55
#CELL
  mstr_ttl ttl1g07_a *
  page151_i56
#ISCELL
  mstr_standard offpage *
  page151_i57
#CELL
  mstr_discrete cap *
  page151_i58
#ISCELL
  mstr_standard offpage *
  page151_i59
#ISCELL
  mstr_standard offpage *
  page151_i60
#ISCELL
  mstr_standard offpage *
  page151_i61
#ISCELL
  mstr_standard offpage *
  page151_i62
#ISCELL
  mstr_standard offpage *
  page151_i63
#ISCELL
  mstr_standard offpage *
  page151_i64
#ISCELL
  mstr_standard offpage *
  page151_i65
#ISCELL
  mstr_standard offpage *
  page151_i66
#ISCELL
  mstr_standard offpage *
  page151_i67
#ISCELL
  mstr_standard offpage *
  page151_i68
#ISCELL
  mstr_standard offpage *
  page151_i69
#ISCELL
  mstr_standard offpage *
  page151_i70
#ISCELL
  mstr_standard offpage *
  page151_i71
#ISCELL
  mstr_standard offpage *
  page151_i72
#ISCELL
  mstr_standard offpage *
  page151_i73
#ISCELL
  mstr_standard offpage *
  page151_i74
#ISCELL
  mstr_standard offpage *
  page151_i75
#ISCELL
  mstr_standard offpage *
  page151_i76
#ISCELL
  mstr_standard offpage *
  page151_i77
#ISCELL
  mstr_standard offpage *
  page151_i78
#ISCELL
  mstr_standard offpage *
  page151_i79
#ISCELL
  mstr_standard offpage *
  page151_i80
#ISCELL
  mstr_standard offpage *
  page151_i81
#ISCELL
  mstr_standard offpage *
  page151_i82
#ISCELL
  mstr_standard offpage *
  page151_i83
#ISCELL
  mstr_standard offpage *
  page151_i84
#ISCELL
  mstr_symbols gnd *
  page151_i85
#ISCELL
  w_power w_vcc_circle *
  page151_i86
#ISCELL
  w_power w_vcc_circle *
  page151_i88
#ISCELL
  mstr_standard offpage *
  page151_i89
#ISCELL
  mstr_symbols gnd *
  page151_i91
#ISCELL
  mstr_standard offpage *
  page151_i92
#ISCELL
  mstr_standard offpage *
  page151_i93
#ISCELL
  mstr_standard offpage *
  page151_i94
#ISCELL
  mstr_standard offpage *
  page151_i95
#ISCELL
  mstr_standard offpage *
  page151_i96
#ISCELL
  mstr_standard offpage *
  page151_i97
#ISCELL
  mstr_standard offpage *
  page151_i98
#ISCELL
  mstr_standard offpage *
  page151_i99
